(kicad_pcb
	(version 20260206)
	(generator "pcbnew")
	(generator_version "10.0")
	(general
		(thickness 1.6)
		(legacy_teardrops no)
	)
	(paper "A4")
	(title_block
		(title "01162023_DA0F0TEBIF0_F0T_Expander_BD_F_brd_V02_OCP.brd")
		(comment 1 "Grand Teton / footprints 1315-1320 of 9728")
	)
	(layers
		(0 "F.Cu" signal "TOP")
		(4 "In1.Cu" signal "GND")
		(6 "In2.Cu" signal "VCC")
		(8 "In3.Cu" signal "VCC1")
		(10 "In4.Cu" signal "GND1")
		(12 "In5.Cu" signal "IN1")
		(14 "In6.Cu" signal "GND2")
		(16 "In7.Cu" signal "IN2")
		(18 "In8.Cu" signal "GND3")
		(20 "In9.Cu" signal "IN3")
		(22 "In10.Cu" signal "GND4")
		(24 "In11.Cu" signal "IN4")
		(26 "In12.Cu" signal "GND5")
		(28 "In13.Cu" signal "IN5")
		(30 "In14.Cu" signal "GND6")
		(32 "In15.Cu" signal "IN6")
		(34 "In16.Cu" signal "GND7")
		(2 "B.Cu" signal "BOTTOM")
		(9 "F.Adhes" user "F.Adhesive")
		(11 "B.Adhes" user "B.Adhesive")
		(13 "F.Paste" user "Package Geometry/Pastemask Top")
		(15 "B.Paste" user "Package Geometry/Pastemask Bottom")
		(5 "F.SilkS" user "Ref Des/Silkscreen Top")
		(7 "B.SilkS" user "Ref Des/Silkscreen Bottom")
		(1 "F.Mask" user "Board Geometry/Soldermask Top")
		(3 "B.Mask" user "Board Geometry/Soldermask Bottom")
		(17 "Dwgs.User" user "User.Drawings")
		(19 "Cmts.User" user "User.Comments")
		(21 "Eco1.User" user "User.Eco1")
		(23 "Eco2.User" user "User.Eco2")
		(25 "Edge.Cuts" user "Board Geometry/Outline")
		(27 "Margin" user)
		(31 "F.CrtYd" user "Package Geometry/Place Bound Top")
		(29 "B.CrtYd" user "Package Geometry/Place Bound Bottom")
		(35 "F.Fab" user "Ref Des/Assembly Top")
		(33 "B.Fab" user "Ref Des/Assembly Bottom")
	)
	(footprint ""
		(layer "F.Cu")
		(at 338.074 -172.085 180)
		(property "Reference" "R4780"
			(at 0 0 180)
			(layer "F.SilkS")
			(hide yes)
			(effects
				(font
					(size 1.27 1.27)
				)
			)
		)
		(property "Value" ""
			(at 0 0 180)
			(layer "F.Fab")
			(effects
				(font
					(size 1.27 1.27)
				)
			)
		)
		(duplicate_pad_numbers_are_jumpers no)
		(fp_line
			(start 0.7874 0.4064)
			(end -0.7874 0.4064)
			(stroke
				(width 0.1524)
				(type default)
			)
			(layer "F.SilkS")
		)
		(fp_line
			(start 0.7874 -0.4064)
			(end 0.7874 0.4064)
			(stroke
				(width 0.1524)
				(type default)
			)
			(layer "F.SilkS")
		)
		(fp_line
			(start -0.7874 0.4064)
			(end -0.7874 -0.4064)
			(stroke
				(width 0.1524)
				(type default)
			)
			(layer "F.SilkS")
		)
		(fp_line
			(start -0.7874 -0.4064)
			(end 0.7874 -0.4064)
			(stroke
				(width 0.1524)
				(type default)
			)
			(layer "F.SilkS")
		)
		(fp_line
			(start 0.67945 0.3048)
			(end 0.120396 0.3048)
			(stroke
				(width 0.1)
				(type default)
			)
			(layer "F.Fab")
		)
		(fp_line
			(start 0.67945 -0.3048)
			(end 0.67945 0.3048)
			(stroke
				(width 0.1)
				(type default)
			)
			(layer "F.Fab")
		)
		(fp_line
			(start 0.12065 -0.2794)
			(end 0.12065 -0.3048)
			(stroke
				(width 0.1)
				(type default)
			)
			(layer "F.Fab")
		)
		(fp_line
			(start 0.12065 -0.3048)
			(end 0.67945 -0.3048)
			(stroke
				(width 0.1)
				(type default)
			)
			(layer "F.Fab")
		)
		(fp_line
			(start 0.120396 0.3048)
			(end 0.120396 0.2794)
			(stroke
				(width 0.1)
				(type default)
			)
			(layer "F.Fab")
		)
		(fp_line
			(start 0.120396 0.2794)
			(end -0.12065 0.2794)
			(stroke
				(width 0.1)
				(type default)
			)
			(layer "F.Fab")
		)
		(fp_line
			(start -0.12065 0.3048)
			(end -0.67945 0.3048)
			(stroke
				(width 0.1)
				(type default)
			)
			(layer "F.Fab")
		)
		(fp_line
			(start -0.12065 0.2794)
			(end -0.12065 0.3048)
			(stroke
				(width 0.1)
				(type default)
			)
			(layer "F.Fab")
		)
		(fp_line
			(start -0.12065 -0.2794)
			(end 0.12065 -0.2794)
			(stroke
				(width 0.1)
				(type default)
			)
			(layer "F.Fab")
		)
		(fp_line
			(start -0.12065 -0.305054)
			(end -0.12065 -0.2794)
			(stroke
				(width 0.1)
				(type default)
			)
			(layer "F.Fab")
		)
		(fp_line
			(start -0.67945 0.3048)
			(end -0.67945 -0.305054)
			(stroke
				(width 0.1)
				(type default)
			)
			(layer "F.Fab")
		)
		(fp_line
			(start -0.67945 -0.305054)
			(end -0.12065 -0.305054)
			(stroke
				(width 0.1)
				(type default)
			)
			(layer "F.Fab")
		)
		(pad "1" smd circle
			(at -0.40005 0 180)
			(size 0 0)
			(layers "F.Cu" "F.Mask" "F.Paste")
			(net "GND")
		)
		(pad "2" smd circle
			(at 0.40005 0 180)
			(size 0 0)
			(layers "F.Cu" "F.Mask" "F.Paste")
			(net "PCA9555_1_PEX2_A2")
		)
	)
	(footprint ""
		(layer "F.Cu")
		(at 268.445742 -258.463034)
		(property "Reference" "C3393"
			(at 0 0 0)
			(layer "F.SilkS")
			(hide yes)
			(effects
				(font
					(size 1.27 1.27)
				)
			)
		)
		(property "Value" ""
			(at 0 0 0)
			(layer "F.Fab")
			(effects
				(font
					(size 1.27 1.27)
				)
			)
		)
		(duplicate_pad_numbers_are_jumpers no)
		(fp_line
			(start -1.2954 -0.5842)
			(end 1.2954 -0.5842)
			(stroke
				(width 0.1524)
				(type default)
			)
			(layer "F.SilkS")
		)
		(fp_line
			(start -1.2954 0.5842)
			(end -1.2954 -0.5842)
			(stroke
				(width 0.1524)
				(type default)
			)
			(layer "F.SilkS")
		)
		(fp_line
			(start 1.2954 -0.5842)
			(end 1.2954 0.5842)
			(stroke
				(width 0.1524)
				(type default)
			)
			(layer "F.SilkS")
		)
		(fp_line
			(start 1.2954 0.5842)
			(end -1.2954 0.5842)
			(stroke
				(width 0.1524)
				(type default)
			)
			(layer "F.SilkS")
		)
		(fp_line
			(start -1.1938 -0.4064)
			(end -0.8636 -0.4064)
			(stroke
				(width 0.1)
				(type default)
			)
			(layer "F.Fab")
		)
		(fp_line
			(start -1.1938 0.4064)
			(end -1.1938 -0.4064)
			(stroke
				(width 0.1)
				(type default)
			)
			(layer "F.Fab")
		)
		(fp_line
			(start -0.8636 -0.4572)
			(end 0.8636 -0.4572)
			(stroke
				(width 0.1)
				(type default)
			)
			(layer "F.Fab")
		)
		(fp_line
			(start -0.8636 -0.4064)
			(end -0.8636 -0.4572)
			(stroke
				(width 0.1)
				(type default)
			)
			(layer "F.Fab")
		)
		(fp_line
			(start -0.8636 0.4064)
			(end -1.1938 0.4064)
			(stroke
				(width 0.1)
				(type default)
			)
			(layer "F.Fab")
		)
		(fp_line
			(start -0.8636 0.4572)
			(end -0.8636 0.4064)
			(stroke
				(width 0.1)
				(type default)
			)
			(layer "F.Fab")
		)
		(fp_line
			(start 0.8636 -0.4572)
			(end 0.8636 -0.4064)
			(stroke
				(width 0.1)
				(type default)
			)
			(layer "F.Fab")
		)
		(fp_line
			(start 0.8636 -0.4064)
			(end 1.1938 -0.4064)
			(stroke
				(width 0.1)
				(type default)
			)
			(layer "F.Fab")
		)
		(fp_line
			(start 0.8636 0.4064)
			(end 0.8636 0.4572)
			(stroke
				(width 0.1)
				(type default)
			)
			(layer "F.Fab")
		)
		(fp_line
			(start 0.8636 0.4572)
			(end -0.8636 0.4572)
			(stroke
				(width 0.1)
				(type default)
			)
			(layer "F.Fab")
		)
		(fp_line
			(start 1.1938 -0.4064)
			(end 1.1938 0.4064)
			(stroke
				(width 0.1)
				(type default)
			)
			(layer "F.Fab")
		)
		(fp_line
			(start 1.1938 0.4064)
			(end 0.8636 0.4064)
			(stroke
				(width 0.1)
				(type default)
			)
			(layer "F.Fab")
		)
		(pad "1" smd rect
			(at -0.7366 0 270)
			(size 0.7112 0.8128)
			(layers "F.Cu" "F.Mask" "F.Paste")
			(net "PCEPLL5_VDDA18_PEX2")
		)
		(pad "2" smd rect
			(at 0.7366 0 270)
			(size 0.7112 0.8128)
			(layers "F.Cu" "F.Mask" "F.Paste")
			(net "GND")
		)
	)
	(footprint ""
		(layer "F.Cu")
		(at 36.638484 -122.79884)
		(property "Reference" "C43"
			(at 0 0 0)
			(layer "F.SilkS")
			(hide yes)
			(effects
				(font
					(size 1.27 1.27)
				)
			)
		)
		(property "Value" ""
			(at 0 0 0)
			(layer "F.Fab")
			(effects
				(font
					(size 1.27 1.27)
				)
			)
		)
		(duplicate_pad_numbers_are_jumpers no)
		(fp_line
			(start -0.299974 -0.150114)
			(end 0.299974 -0.150114)
			(stroke
				(width 0.1)
				(type default)
			)
			(layer "F.Fab")
		)
		(fp_line
			(start -0.299974 0.150114)
			(end -0.299974 -0.150114)
			(stroke
				(width 0.1)
				(type default)
			)
			(layer "F.Fab")
		)
		(fp_line
			(start 0.299974 -0.150114)
			(end 0.299974 0.150114)
			(stroke
				(width 0.1)
				(type default)
			)
			(layer "F.Fab")
		)
		(fp_line
			(start 0.299974 0.150114)
			(end -0.299974 0.150114)
			(stroke
				(width 0.1)
				(type default)
			)
			(layer "F.Fab")
		)
		(pad "1" smd rect
			(at -0.2667 0)
			(size 0.3048 0.381)
			(layers "F.Cu" "F.Mask" "F.Paste")
			(net "P5E_PEX0_STN1_TX_DP<26>")
		)
		(pad "2" smd rect
			(at 0.2667 0)
			(size 0.3048 0.381)
			(layers "F.Cu" "F.Mask" "F.Paste")
			(net "P5E_PEX0_STN1_TX_C_DP<26>")
		)
	)
	(footprint ""
		(layer "F.Cu")
		(at 138.747246 -54.3941)
		(property "Reference" "PU31"
			(at -1.450594 3.01244 0)
			(unlocked yes)
			(layer "F.SilkS")
			(effects
				(font
					(size 0.7874 0.5842)
					(thickness 0.1524)
				)
				(justify left)
			)
		)
		(property "Value" ""
			(at 0 0 0)
			(layer "F.Fab")
			(effects
				(font
					(size 1.27 1.27)
				)
			)
		)
		(duplicate_pad_numbers_are_jumpers no)
		(fp_line
			(start -1.943608 -1.549908)
			(end 1.943608 -1.549908)
			(stroke
				(width 0.1524)
				(type default)
			)
			(layer "F.SilkS")
		)
		(fp_line
			(start -1.943608 1.549908)
			(end -1.943608 -1.549908)
			(stroke
				(width 0.1524)
				(type default)
			)
			(layer "F.SilkS")
		)
		(fp_line
			(start 1.943608 -1.549908)
			(end 1.943608 1.549908)
			(stroke
				(width 0.1524)
				(type default)
			)
			(layer "F.SilkS")
		)
		(fp_line
			(start 1.943608 1.549908)
			(end -1.943608 1.549908)
			(stroke
				(width 0.1524)
				(type default)
			)
			(layer "F.SilkS")
		)
		(fp_poly
			(pts
				(xy -2.019808 -1.549908) (xy -1.257808 -1.549908) (xy -1.257808 -1.880108) (xy -2.019808 -1.880108)
			)
			(stroke
				(width 0)
				(type default)
			)
			(fill yes)
			(layer "F.SilkS")
		)
		(fp_line
			(start -1.549908 -1.549908)
			(end 1.549908 -1.549908)
			(stroke
				(width 0.1)
				(type default)
			)
			(layer "F.Fab")
		)
		(fp_line
			(start -1.549908 1.549908)
			(end -1.549908 -1.549908)
			(stroke
				(width 0.1)
				(type default)
			)
			(layer "F.Fab")
		)
		(fp_line
			(start 1.549908 -1.549908)
			(end 1.549908 1.549908)
			(stroke
				(width 0.1)
				(type default)
			)
			(layer "F.Fab")
		)
		(fp_line
			(start 1.549908 1.549908)
			(end -1.549908 1.549908)
			(stroke
				(width 0.1)
				(type default)
			)
			(layer "F.Fab")
		)
		(fp_poly
			(pts
				(xy -2.019808 -1.549908) (xy -1.257808 -1.549908) (xy -1.257808 -1.880108) (xy -2.019808 -1.880108)
			)
			(stroke
				(width 0)
				(type default)
			)
			(fill yes)
			(layer "F.Fab")
		)
		(pad "1" smd rect
			(at -1.500124 -1.249934 270)
			(size 0.2794 0.6096)
			(layers "F.Cu" "F.Mask" "F.Paste")
			(net "P12V_SSD4_R")
		)
		(pad "2" smd rect
			(at -1.500124 -0.750062 270)
			(size 0.2794 0.6096)
			(layers "F.Cu" "F.Mask" "F.Paste")
			(net "P12V_SSD4_R")
		)
		(pad "3" smd rect
			(at -1.500124 -0.249936 270)
			(size 0.2794 0.6096)
			(layers "F.Cu" "F.Mask" "F.Paste")
			(net "P12V_SSD4_R")
		)
		(pad "4" smd rect
			(at -1.500124 0.249936 270)
			(size 0.2794 0.6096)
			(layers "F.Cu" "F.Mask" "F.Paste")
			(net "P12V_SSD4_R")
		)
		(pad "5" smd rect
			(at -1.500124 0.750062 270)
			(size 0.2794 0.6096)
			(layers "F.Cu" "F.Mask" "F.Paste")
			(net "P12V_SSD4_R")
		)
		(pad "6" smd rect
			(at -1.500124 1.249934 270)
			(size 0.2794 0.6096)
			(layers "F.Cu" "F.Mask" "F.Paste")
			(net "GND")
		)
		(pad "7" smd rect
			(at 1.500124 1.249934 270)
			(size 0.2794 0.6096)
			(layers "F.Cu" "F.Mask" "F.Paste")
			(net "P12V_SSD4_SS")
		)
		(pad "8" smd rect
			(at 1.500124 0.750062 270)
			(size 0.2794 0.6096)
			(layers "F.Cu" "F.Mask" "F.Paste")
			(net "PWRGD_P12V_SSD4")
		)
		(pad "9" smd rect
			(at 1.500124 0.249936 270)
			(size 0.2794 0.6096)
			(layers "F.Cu" "F.Mask" "F.Paste")
			(net "P12V_SSD4_OCP")
		)
		(pad "10" smd rect
			(at 1.500124 -0.249936 270)
			(size 0.2794 0.6096)
			(layers "F.Cu" "F.Mask" "F.Paste")
			(net "P5V_AUX")
		)
		(pad "11" smd rect
			(at 1.500124 -0.750062 270)
			(size 0.2794 0.6096)
			(layers "F.Cu" "F.Mask" "F.Paste")
			(net "SSD4_PWR_EN_R")
		)
		(pad "12" smd rect
			(at 1.500124 -1.249934 270)
			(size 0.2794 0.6096)
			(layers "F.Cu" "F.Mask" "F.Paste")
			(net "P12V_AUX")
		)
		(pad "13" smd rect
			(at 0 0)
			(size 1.9812 2.7178)
			(layers "F.Cu" "F.Mask" "F.Paste")
			(net "P12V_AUX")
		)
		(zone
			(layer "F.Cu")
			(hatch none 0.5)
			(connect_pads
				(clearance 0)
			)
			(min_thickness 0.25)
			(keepout
				(tracks not_allowed)
				(vias allowed)
				(pads allowed)
				(copperpour not_allowed)
				(footprints allowed)
			)
			(placement
				(enabled no)
				(sheetname "")
			)
			(fill
				(thermal_gap 0.5)
				(thermal_bridge_width 0.5)
				(island_removal_mode 0)
			)
			(polygon
				(pts
					(xy 139.890246 -55.9435) (xy 139.890246 -55.8165) (xy 139.890246 -52.8447) (xy 139.890246 -52.844192)
					(xy 137.604246 -52.844192) (xy 137.604246 -52.8447) (xy 137.604246 -52.9717) (xy 137.604246 -54.3941)
					(xy 137.705846 -54.3941) (xy 137.705846 -52.9717) (xy 139.788646 -52.9717) (xy 139.788646 -55.8165)
					(xy 137.705846 -55.8165) (xy 137.705846 -54.4195) (xy 137.604246 -54.4195) (xy 137.604246 -55.8165)
					(xy 137.604246 -55.9435) (xy 137.604246 -55.944008) (xy 139.890246 -55.944008)
				)
			)
		)
	)
	(footprint ""
		(layer "F.Cu")
		(at 438.164732 -350.098614 90)
		(property "Reference" "C799"
			(at 0 0 90)
			(layer "F.SilkS")
			(hide yes)
			(effects
				(font
					(size 1.27 1.27)
				)
			)
		)
		(property "Value" ""
			(at 0 0 90)
			(layer "F.Fab")
			(effects
				(font
					(size 1.27 1.27)
				)
			)
		)
		(duplicate_pad_numbers_are_jumpers no)
		(fp_line
			(start 0.299974 -0.150114)
			(end 0.299974 0.150114)
			(stroke
				(width 0.1)
				(type default)
			)
			(layer "F.Fab")
		)
		(fp_line
			(start -0.299974 -0.150114)
			(end 0.299974 -0.150114)
			(stroke
				(width 0.1)
				(type default)
			)
			(layer "F.Fab")
		)
		(fp_line
			(start 0.299974 0.150114)
			(end -0.299974 0.150114)
			(stroke
				(width 0.1)
				(type default)
			)
			(layer "F.Fab")
		)
		(fp_line
			(start -0.299974 0.150114)
			(end -0.299974 -0.150114)
			(stroke
				(width 0.1)
				(type default)
			)
			(layer "F.Fab")
		)
		(pad "1" smd rect
			(at -0.2667 0 90)
			(size 0.3048 0.381)
			(layers "F.Cu" "F.Mask" "F.Paste")
			(net "P5E_PEX3_STN7_TX_DN<125>")
		)
		(pad "2" smd rect
			(at 0.2667 0 90)
			(size 0.3048 0.381)
			(layers "F.Cu" "F.Mask" "F.Paste")
			(net "P5E_PEX3_STN7_TX_C_DN<125>")
		)
	)
	(footprint ""
		(layer "F.Cu")
		(at 259.130038 -297.205908 -90)
		(property "Reference" "C3401"
			(at 0 0 270)
			(layer "F.SilkS")
			(hide yes)
			(effects
				(font
					(size 1.27 1.27)
				)
			)
		)
		(property "Value" ""
			(at 0 0 270)
			(layer "F.Fab")
			(effects
				(font
					(size 1.27 1.27)
				)
			)
		)
		(duplicate_pad_numbers_are_jumpers no)
		(fp_line
			(start -1.2954 0.5842)
			(end -1.2954 -0.5842)
			(stroke
				(width 0.1524)
				(type default)
			)
			(layer "F.SilkS")
		)
		(fp_line
			(start 1.2954 0.5842)
			(end -1.2954 0.5842)
			(stroke
				(width 0.1524)
				(type default)
			)
			(layer "F.SilkS")
		)
		(fp_line
			(start -1.2954 -0.5842)
			(end 1.2954 -0.5842)
			(stroke
				(width 0.1524)
				(type default)
			)
			(layer "F.SilkS")
		)
		(fp_line
			(start 1.2954 -0.5842)
			(end 1.2954 0.5842)
			(stroke
				(width 0.1524)
				(type default)
			)
			(layer "F.SilkS")
		)
		(fp_line
			(start -0.8636 0.4572)
			(end -0.8636 0.4064)
			(stroke
				(width 0.1)
				(type default)
			)
			(layer "F.Fab")
		)
		(fp_line
			(start 0.8636 0.4572)
			(end -0.8636 0.4572)
			(stroke
				(width 0.1)
				(type default)
			)
			(layer "F.Fab")
		)
		(fp_line
			(start -1.1938 0.4064)
			(end -1.1938 -0.4064)
			(stroke
				(width 0.1)
				(type default)
			)
			(layer "F.Fab")
		)
		(fp_line
			(start -0.8636 0.4064)
			(end -1.1938 0.4064)
			(stroke
				(width 0.1)
				(type default)
			)
			(layer "F.Fab")
		)
		(fp_line
			(start 0.8636 0.4064)
			(end 0.8636 0.4572)
			(stroke
				(width 0.1)
				(type default)
			)
			(layer "F.Fab")
		)
		(fp_line
			(start 1.1938 0.4064)
			(end 0.8636 0.4064)
			(stroke
				(width 0.1)
				(type default)
			)
			(layer "F.Fab")
		)
		(fp_line
			(start -1.1938 -0.4064)
			(end -0.8636 -0.4064)
			(stroke
				(width 0.1)
				(type default)
			)
			(layer "F.Fab")
		)
		(fp_line
			(start -0.8636 -0.4064)
			(end -0.8636 -0.4572)
			(stroke
				(width 0.1)
				(type default)
			)
			(layer "F.Fab")
		)
		(fp_line
			(start 0.8636 -0.4064)
			(end 1.1938 -0.4064)
			(stroke
				(width 0.1)
				(type default)
			)
			(layer "F.Fab")
		)
		(fp_line
			(start 1.1938 -0.4064)
			(end 1.1938 0.4064)
			(stroke
				(width 0.1)
				(type default)
			)
			(layer "F.Fab")
		)
		(fp_line
			(start -0.8636 -0.4572)
			(end 0.8636 -0.4572)
			(stroke
				(width 0.1)
				(type default)
			)
			(layer "F.Fab")
		)
		(fp_line
			(start 0.8636 -0.4572)
			(end 0.8636 -0.4064)
			(stroke
				(width 0.1)
				(type default)
			)
			(layer "F.Fab")
		)
		(pad "1" smd rect
			(at -0.7366 0 180)
			(size 0.7112 0.8128)
			(layers "F.Cu" "F.Mask" "F.Paste")
			(net "P1V8_PLL0_PEX2")
		)
		(pad "2" smd rect
			(at 0.7366 0 180)
			(size 0.7112 0.8128)
			(layers "F.Cu" "F.Mask" "F.Paste")
			(net "GND")
		)
	)
)
